(kicad_pcb
	(version 20260206)
	(generator "pcbnew")
	(generator_version "10.0")
	(general
		(thickness 1.6)
		(legacy_teardrops no)
	)
	(paper "A4")
	(title_block
		(title "baseboard — 13948-1b.1110WZS1818.brd")
		(comment 1 "Honey Badger (Wiwynn) / footprints 2151-2157 of 2523")
	)
	(layers
		(0 "F.Cu" signal "TOP")
		(4 "In1.Cu" signal "L2GND")
		(6 "In2.Cu" signal "L3")
		(8 "In3.Cu" signal "L4VCC")
		(10 "In4.Cu" signal "L5VCC")
		(12 "In5.Cu" signal "L6")
		(14 "In6.Cu" signal "L7GND")
		(2 "B.Cu" signal "BOTTOM")
		(9 "F.Adhes" user "F.Adhesive")
		(11 "B.Adhes" user "B.Adhesive")
		(13 "F.Paste" user "Package Geometry/Pastemask Top")
		(15 "B.Paste" user "Package Geometry/Pastemask Bottom")
		(5 "F.SilkS" user "Ref Des/Silkscreen Top")
		(7 "B.SilkS" user "Ref Des/Silkscreen Bottom")
		(1 "F.Mask" user "Board Geometry/Soldermask Top")
		(3 "B.Mask" user "Board Geometry/Soldermask Bottom")
		(17 "Dwgs.User" user "User.Drawings")
		(19 "Cmts.User" user "User.Comments")
		(21 "Eco1.User" user "User.Eco1")
		(23 "Eco2.User" user "User.Eco2")
		(25 "Edge.Cuts" user "Board Geometry/Outline")
		(27 "Margin" user)
		(31 "F.CrtYd" user "Package Geometry/Place Bound Top")
		(29 "B.CrtYd" user "Package Geometry/Place Bound Bottom")
		(35 "F.Fab" user "Ref Des/Assembly Top")
		(33 "B.Fab" user "Ref Des/Assembly Bottom")
	)
	(footprint ""
		(layer "B.Cu")
		(at 310.896 -185.674 90)
		(property "Reference" "R303"
			(at 0 0 90)
			(layer "B.SilkS")
			(hide yes)
			(effects
				(font
					(size 1.27 1.27)
				)
				(justify mirror)
			)
		)
		(property "Value" "0R2J-2-GP"
			(at -0.064008 -3.993896 90)
			(unlocked yes)
			(layer "B.Fab")
			(hide yes)
			(effects
				(font
					(size 1.016 1.016)
					(thickness 0.1524)
				)
				(justify mirror)
			)
		)
		(property "Device Type" "R402H16"
			(at -0.064008 -5.517896 90)
			(unlocked yes)
			(layer "B.Fab")
			(hide yes)
			(effects
				(font
					(size 1.016 1.016)
					(thickness 0.1524)
				)
				(justify mirror)
			)
		)
		(duplicate_pad_numbers_are_jumpers no)
		(fp_line
			(start 0.508 -0.9398)
			(end 0.508 0.9398)
			(stroke
				(width 0.1524)
				(type default)
			)
			(layer "B.SilkS")
		)
		(fp_line
			(start -0.508 -0.9398)
			(end 0.508 -0.9398)
			(stroke
				(width 0.1524)
				(type default)
			)
			(layer "B.SilkS")
		)
		(fp_rect
			(start 0.508 0.9398)
			(end -0.508 -0.9398)
			(stroke
				(width 0)
				(type default)
			)
			(fill no)
			(layer "B.CrtYd")
		)
		(fp_rect
			(start 0.508 0.9398)
			(end -0.508 -0.9398)
			(stroke
				(width 0)
				(type default)
			)
			(fill no)
			(layer "B.Fab")
		)
		(pad "1" smd custom
			(at 0 -0.4445 270)
			(size 0.1397 0.1397)
			(layers "B.Cu" "B.Mask" "B.Paste")
			(net "HB0_R_IN1")
			(options
				(clearance outline)
				(anchor circle)
			)
			(primitives
				(gr_poly
					(pts
						(arc
							(start -0.1778 0.2794)
							(mid -0.249642 0.249642)
							(end -0.2794 0.1778)
						)
						(arc
							(start -0.2794 -0.1778)
							(mid -0.249642 -0.249642)
							(end -0.1778 -0.2794)
						)
						(arc
							(start 0.1778 -0.2794)
							(mid 0.249642 -0.249642)
							(end 0.2794 -0.1778)
						)
						(arc
							(start 0.2794 0.1778)
							(mid 0.249642 0.249642)
							(end 0.1778 0.2794)
						)
					)
					(width 0)
					(fill yes)
				)
			)
		)
		(pad "2" smd custom
			(at 0 0.4445 270)
			(size 0.1397 0.1397)
			(layers "B.Cu" "B.Mask" "B.Paste")
			(net "PEER_1A_2A_HB")
			(options
				(clearance outline)
				(anchor circle)
			)
			(primitives
				(gr_poly
					(pts
						(arc
							(start -0.1778 0.2794)
							(mid -0.249642 0.249642)
							(end -0.2794 0.1778)
						)
						(arc
							(start -0.2794 -0.1778)
							(mid -0.249642 -0.249642)
							(end -0.1778 -0.2794)
						)
						(arc
							(start 0.1778 -0.2794)
							(mid 0.249642 -0.249642)
							(end 0.2794 -0.1778)
						)
						(arc
							(start 0.2794 0.1778)
							(mid 0.249642 0.249642)
							(end 0.1778 0.2794)
						)
					)
					(width 0)
					(fill yes)
				)
			)
		)
	)
	(footprint ""
		(layer "B.Cu")
		(at 117.73789 -89.86774)
		(property "Reference" "SC1258"
			(at 0 0 0)
			(layer "B.SilkS")
			(hide yes)
			(effects
				(font
					(size 1.27 1.27)
				)
				(justify mirror)
			)
		)
		(property "Value" "SCD1U6D3V1KX-GP"
			(at 2.8321 -1.7399 0)
			(unlocked yes)
			(layer "B.Fab")
			(hide yes)
			(effects
				(font
					(size 1.016 1.016)
					(thickness 0.1524)
				)
				(justify mirror)
			)
		)
		(property "Device Type" "C0201H13"
			(at 2.8321 -3.2639 0)
			(unlocked yes)
			(layer "B.Fab")
			(hide yes)
			(effects
				(font
					(size 1.016 1.016)
					(thickness 0.1524)
				)
				(justify mirror)
			)
		)
		(duplicate_pad_numbers_are_jumpers no)
		(fp_rect
			(start 0.2794 0.6477)
			(end -0.2794 -0.6477)
			(stroke
				(width 0)
				(type default)
			)
			(fill no)
			(layer "B.CrtYd")
		)
		(fp_rect
			(start 0.2794 0.6477)
			(end -0.2794 -0.6477)
			(stroke
				(width 0)
				(type default)
			)
			(fill no)
			(layer "B.Fab")
		)
		(pad "1" smd custom
			(at 0 -0.2794 180)
			(size 0.0762 0.0762)
			(layers "B.Cu" "B.Mask" "B.Paste")
			(net "P0V9_E")
			(options
				(clearance outline)
				(anchor circle)
			)
			(primitives
				(gr_poly
					(pts
						(arc
							(start 0.1524 0.127)
							(mid 0.137521 0.162921)
							(end 0.1016 0.1778)
						)
						(arc
							(start -0.1016 0.1778)
							(mid -0.137521 0.162921)
							(end -0.1524 0.127)
						)
						(arc
							(start -0.1524 -0.127)
							(mid -0.137521 -0.162921)
							(end -0.1016 -0.1778)
						)
						(arc
							(start 0.1016 -0.1778)
							(mid 0.137521 -0.162921)
							(end 0.1524 -0.127)
						)
					)
					(width 0)
					(fill yes)
				)
			)
		)
		(pad "2" smd custom
			(at 0 0.2794 180)
			(size 0.0762 0.0762)
			(layers "B.Cu" "B.Mask" "B.Paste")
			(net "GND")
			(options
				(clearance outline)
				(anchor circle)
			)
			(primitives
				(gr_poly
					(pts
						(arc
							(start 0.1524 0.127)
							(mid 0.137521 0.162921)
							(end 0.1016 0.1778)
						)
						(arc
							(start -0.1016 0.1778)
							(mid -0.137521 0.162921)
							(end -0.1524 0.127)
						)
						(arc
							(start -0.1524 -0.127)
							(mid -0.137521 -0.162921)
							(end -0.1016 -0.1778)
						)
						(arc
							(start 0.1016 -0.1778)
							(mid 0.137521 -0.162921)
							(end 0.1524 -0.127)
						)
					)
					(width 0)
					(fill yes)
				)
			)
		)
	)
	(footprint ""
		(layer "B.Cu")
		(at 118.218966 -32.258)
		(property "Reference" "STP28"
			(at 0 0 0)
			(layer "B.SilkS")
			(hide yes)
			(effects
				(font
					(size 1.27 1.27)
				)
				(justify mirror)
			)
		)
		(property "Value" "TPAD28"
			(at -0.0127 -1.8034 0)
			(unlocked yes)
			(layer "B.Fab")
			(hide yes)
			(effects
				(font
					(size 1.016 1.016)
					(thickness 0.1524)
				)
				(justify mirror)
			)
		)
		(property "Device Type" "TPAD28"
			(at -0.0127 -3.3274 0)
			(unlocked yes)
			(layer "B.Fab")
			(hide yes)
			(effects
				(font
					(size 1.016 1.016)
					(thickness 0.1524)
				)
				(justify mirror)
			)
		)
		(duplicate_pad_numbers_are_jumpers no)
		(fp_poly
			(pts
				(arc
					(start 0.3556 0)
					(mid -0.3556 0)
					(end 0.3556 0)
				)
			)
			(stroke
				(width 0)
				(type default)
			)
			(fill no)
			(layer "B.CrtYd")
		)
		(fp_poly
			(pts
				(arc
					(start 0.6096 0)
					(mid -0.6096 0)
					(end 0.6096 0)
				)
			)
			(stroke
				(width 0)
				(type default)
			)
			(fill no)
			(layer "B.Fab")
		)
		(pad "1" smd circle
			(at 0 0 180)
			(size 0.7112 0.7112)
			(layers "B.Cu" "B.Mask" "B.Paste")
			(net "UART_SERCLK")
		)
	)
	(footprint ""
		(layer "B.Cu")
		(at 105.264966 -43.307 90)
		(property "Reference" "SC1029"
			(at 0 0 90)
			(layer "B.SilkS")
			(hide yes)
			(effects
				(font
					(size 1.27 1.27)
				)
				(justify mirror)
			)
		)
		(property "Value" "SC1KP50V2KX-1GP"
			(at -1.1811 -2.7051 90)
			(unlocked yes)
			(layer "B.Fab")
			(hide yes)
			(effects
				(font
					(size 1.016 1.016)
					(thickness 0.1524)
				)
				(justify mirror)
			)
		)
		(property "Device Type" "C402H22"
			(at -1.1811 -4.2291 90)
			(unlocked yes)
			(layer "B.Fab")
			(hide yes)
			(effects
				(font
					(size 1.016 1.016)
					(thickness 0.1524)
				)
				(justify mirror)
			)
		)
		(duplicate_pad_numbers_are_jumpers no)
		(fp_rect
			(start 0.4318 0.9525)
			(end -0.4318 -0.9525)
			(stroke
				(width 0)
				(type default)
			)
			(fill no)
			(layer "B.CrtYd")
		)
		(fp_rect
			(start 0.4318 0.9525)
			(end -0.4318 -0.9525)
			(stroke
				(width 0)
				(type default)
			)
			(fill no)
			(layer "B.Fab")
		)
		(pad "1" smd custom
			(at 0 -0.4445 270)
			(size 0.1524 0.1524)
			(layers "B.Cu" "B.Mask" "B.Paste")
			(net "P0V955_C")
			(options
				(clearance outline)
				(anchor circle)
			)
			(primitives
				(gr_poly
					(pts
						(arc
							(start 0.3048 0.2032)
							(mid 0.275042 0.275042)
							(end 0.2032 0.3048)
						)
						(arc
							(start -0.2032 0.3048)
							(mid -0.275042 0.275042)
							(end -0.3048 0.2032)
						)
						(arc
							(start -0.3048 -0.2032)
							(mid -0.275042 -0.275042)
							(end -0.2032 -0.3048)
						)
						(arc
							(start 0.2032 -0.3048)
							(mid 0.275042 -0.275042)
							(end 0.3048 -0.2032)
						)
					)
					(width 0)
					(fill yes)
				)
			)
		)
		(pad "2" smd custom
			(at 0 0.4445 270)
			(size 0.1524 0.1524)
			(layers "B.Cu" "B.Mask" "B.Paste")
			(net "GND")
			(options
				(clearance outline)
				(anchor circle)
			)
			(primitives
				(gr_poly
					(pts
						(arc
							(start 0.3048 0.2032)
							(mid 0.275042 0.275042)
							(end 0.2032 0.3048)
						)
						(arc
							(start -0.2032 0.3048)
							(mid -0.275042 0.275042)
							(end -0.3048 0.2032)
						)
						(arc
							(start -0.3048 -0.2032)
							(mid -0.275042 -0.275042)
							(end -0.2032 -0.3048)
						)
						(arc
							(start 0.2032 -0.3048)
							(mid 0.275042 -0.275042)
							(end 0.3048 -0.2032)
						)
					)
					(width 0)
					(fill yes)
				)
			)
		)
	)
	(footprint ""
		(layer "B.Cu")
		(at 98.305366 -39.0398 180)
		(property "Reference" "SC955"
			(at 0 0 0)
			(layer "B.SilkS")
			(hide yes)
			(effects
				(font
					(size 1.27 1.27)
				)
				(justify mirror)
			)
		)
		(property "Value" "SCD1U6D3V1KX-GP"
			(at 2.8321 -1.7399 180)
			(unlocked yes)
			(layer "B.Fab")
			(hide yes)
			(effects
				(font
					(size 1.016 1.016)
					(thickness 0.1524)
				)
				(justify mirror)
			)
		)
		(property "Device Type" "C0201H13"
			(at 2.8321 -3.2639 180)
			(unlocked yes)
			(layer "B.Fab")
			(hide yes)
			(effects
				(font
					(size 1.016 1.016)
					(thickness 0.1524)
				)
				(justify mirror)
			)
		)
		(duplicate_pad_numbers_are_jumpers no)
		(fp_rect
			(start 0.2794 0.6477)
			(end -0.2794 -0.6477)
			(stroke
				(width 0)
				(type default)
			)
			(fill no)
			(layer "B.CrtYd")
		)
		(fp_rect
			(start 0.2794 0.6477)
			(end -0.2794 -0.6477)
			(stroke
				(width 0)
				(type default)
			)
			(fill no)
			(layer "B.Fab")
		)
		(pad "1" smd custom
			(at 0 -0.2794)
			(size 0.0762 0.0762)
			(layers "B.Cu" "B.Mask" "B.Paste")
			(net "PCE_AVDD")
			(options
				(clearance outline)
				(anchor circle)
			)
			(primitives
				(gr_poly
					(pts
						(arc
							(start 0.1524 0.127)
							(mid 0.137521 0.162921)
							(end 0.1016 0.1778)
						)
						(arc
							(start -0.1016 0.1778)
							(mid -0.137521 0.162921)
							(end -0.1524 0.127)
						)
						(arc
							(start -0.1524 -0.127)
							(mid -0.137521 -0.162921)
							(end -0.1016 -0.1778)
						)
						(arc
							(start 0.1016 -0.1778)
							(mid 0.137521 -0.162921)
							(end 0.1524 -0.127)
						)
					)
					(width 0)
					(fill yes)
				)
			)
		)
		(pad "2" smd custom
			(at 0 0.2794)
			(size 0.0762 0.0762)
			(layers "B.Cu" "B.Mask" "B.Paste")
			(net "GND")
			(options
				(clearance outline)
				(anchor circle)
			)
			(primitives
				(gr_poly
					(pts
						(arc
							(start 0.1524 0.127)
							(mid 0.137521 0.162921)
							(end 0.1016 0.1778)
						)
						(arc
							(start -0.1016 0.1778)
							(mid -0.137521 0.162921)
							(end -0.1524 0.127)
						)
						(arc
							(start -0.1524 -0.127)
							(mid -0.137521 -0.162921)
							(end -0.1016 -0.1778)
						)
						(arc
							(start 0.1016 -0.1778)
							(mid 0.137521 -0.162921)
							(end 0.1524 -0.127)
						)
					)
					(width 0)
					(fill yes)
				)
			)
		)
	)
	(footprint ""
		(layer "B.Cu")
		(at 83.693 -74.295 180)
		(property "Reference" "SR929"
			(at 0 0 0)
			(layer "B.SilkS")
			(hide yes)
			(effects
				(font
					(size 1.27 1.27)
				)
				(justify mirror)
			)
		)
		(property "Value" "0R2J-2-GP"
			(at -0.064008 -3.993896 180)
			(unlocked yes)
			(layer "B.Fab")
			(hide yes)
			(effects
				(font
					(size 1.016 1.016)
					(thickness 0.1524)
				)
				(justify mirror)
			)
		)
		(property "Device Type" "R402H16"
			(at -0.064008 -5.517896 180)
			(unlocked yes)
			(layer "B.Fab")
			(hide yes)
			(effects
				(font
					(size 1.016 1.016)
					(thickness 0.1524)
				)
				(justify mirror)
			)
		)
		(duplicate_pad_numbers_are_jumpers no)
		(fp_line
			(start 0.508 -0.9398)
			(end 0.508 0.9398)
			(stroke
				(width 0.1524)
				(type default)
			)
			(layer "B.SilkS")
		)
		(fp_line
			(start -0.508 -0.9398)
			(end 0.508 -0.9398)
			(stroke
				(width 0.1524)
				(type default)
			)
			(layer "B.SilkS")
		)
		(fp_rect
			(start 0.508 0.9398)
			(end -0.508 -0.9398)
			(stroke
				(width 0)
				(type default)
			)
			(fill no)
			(layer "B.CrtYd")
		)
		(fp_rect
			(start 0.508 0.9398)
			(end -0.508 -0.9398)
			(stroke
				(width 0)
				(type default)
			)
			(fill no)
			(layer "B.Fab")
		)
		(pad "1" smd custom
			(at 0 -0.4445)
			(size 0.1397 0.1397)
			(layers "B.Cu" "B.Mask" "B.Paste")
			(net "PG_STAT")
			(options
				(clearance outline)
				(anchor circle)
			)
			(primitives
				(gr_poly
					(pts
						(arc
							(start -0.1778 0.2794)
							(mid -0.249642 0.249642)
							(end -0.2794 0.1778)
						)
						(arc
							(start -0.2794 -0.1778)
							(mid -0.249642 -0.249642)
							(end -0.1778 -0.2794)
						)
						(arc
							(start 0.1778 -0.2794)
							(mid 0.249642 -0.249642)
							(end 0.2794 -0.1778)
						)
						(arc
							(start 0.2794 0.1778)
							(mid 0.249642 0.249642)
							(end 0.1778 0.2794)
						)
					)
					(width 0)
					(fill yes)
				)
			)
		)
		(pad "2" smd custom
			(at 0 0.4445)
			(size 0.1397 0.1397)
			(layers "B.Cu" "B.Mask" "B.Paste")
			(net "P0V955_C_PG_R")
			(options
				(clearance outline)
				(anchor circle)
			)
			(primitives
				(gr_poly
					(pts
						(arc
							(start -0.1778 0.2794)
							(mid -0.249642 0.249642)
							(end -0.2794 0.1778)
						)
						(arc
							(start -0.2794 -0.1778)
							(mid -0.249642 -0.249642)
							(end -0.1778 -0.2794)
						)
						(arc
							(start 0.1778 -0.2794)
							(mid 0.249642 -0.249642)
							(end 0.2794 -0.1778)
						)
						(arc
							(start 0.2794 0.1778)
							(mid 0.249642 0.249642)
							(end 0.1778 0.2794)
						)
					)
					(width 0)
					(fill yes)
				)
			)
		)
	)
	(footprint ""
		(layer "B.Cu")
		(at 112.78997 -75.438)
		(property "Reference" "SR704"
			(at 0 0 0)
			(layer "B.SilkS")
			(hide yes)
			(effects
				(font
					(size 1.27 1.27)
				)
				(justify mirror)
			)
		)
		(property "Value" "10KR2F-2-GP"
			(at -0.064008 -3.993896 0)
			(unlocked yes)
			(layer "B.Fab")
			(hide yes)
			(effects
				(font
					(size 1.016 1.016)
					(thickness 0.1524)
				)
				(justify mirror)
			)
		)
		(property "Device Type" "R402H16"
			(at -0.064008 -5.517896 0)
			(unlocked yes)
			(layer "B.Fab")
			(hide yes)
			(effects
				(font
					(size 1.016 1.016)
					(thickness 0.1524)
				)
				(justify mirror)
			)
		)
		(duplicate_pad_numbers_are_jumpers no)
		(fp_line
			(start -0.508 -0.9398)
			(end 0.508 -0.9398)
			(stroke
				(width 0.1524)
				(type default)
			)
			(layer "B.SilkS")
		)
		(fp_line
			(start 0.508 -0.9398)
			(end 0.508 0.9398)
			(stroke
				(width 0.1524)
				(type default)
			)
			(layer "B.SilkS")
		)
		(fp_rect
			(start 0.508 0.9398)
			(end -0.508 -0.9398)
			(stroke
				(width 0)
				(type default)
			)
			(fill no)
			(layer "B.CrtYd")
		)
		(fp_rect
			(start 0.508 0.9398)
			(end -0.508 -0.9398)
			(stroke
				(width 0)
				(type default)
			)
			(fill no)
			(layer "B.Fab")
		)
		(pad "1" smd custom
			(at 0 -0.4445 180)
			(size 0.1397 0.1397)
			(layers "B.Cu" "B.Mask" "B.Paste")
			(net "P1V8_E")
			(options
				(clearance outline)
				(anchor circle)
			)
			(primitives
				(gr_poly
					(pts
						(arc
							(start -0.1778 0.2794)
							(mid -0.249642 0.249642)
							(end -0.2794 0.1778)
						)
						(arc
							(start -0.2794 -0.1778)
							(mid -0.249642 -0.249642)
							(end -0.1778 -0.2794)
						)
						(arc
							(start 0.1778 -0.2794)
							(mid 0.249642 -0.249642)
							(end 0.2794 -0.1778)
						)
						(arc
							(start 0.2794 0.1778)
							(mid 0.249642 0.249642)
							(end 0.1778 0.2794)
						)
					)
					(width 0)
					(fill yes)
				)
			)
		)
		(pad "2" smd custom
			(at 0 0.4445 180)
			(size 0.1397 0.1397)
			(layers "B.Cu" "B.Mask" "B.Paste")
			(net "EXP_BLINK_OUT")
			(options
				(clearance outline)
				(anchor circle)
			)
			(primitives
				(gr_poly
					(pts
						(arc
							(start -0.1778 0.2794)
							(mid -0.249642 0.249642)
							(end -0.2794 0.1778)
						)
						(arc
							(start -0.2794 -0.1778)
							(mid -0.249642 -0.249642)
							(end -0.1778 -0.2794)
						)
						(arc
							(start 0.1778 -0.2794)
							(mid 0.249642 -0.249642)
							(end 0.2794 -0.1778)
						)
						(arc
							(start 0.2794 0.1778)
							(mid 0.249642 0.249642)
							(end 0.1778 0.2794)
						)
					)
					(width 0)
					(fill yes)
				)
			)
		)
	)
)
